(kicad_pcb
	(version 20260206)
	(generator "pcbnew")
	(generator_version "10.0")
	(general
		(thickness 1.6)
		(legacy_teardrops no)
	)
	(paper "A4")
	(title_block
		(title "01162023_DA0F0TEBIF0_F0T_Expander_BD_F_brd_V02_OCP.brd")
		(comment 1 "Grand Teton / footprints 4814-4819 of 9728")
	)
	(layers
		(0 "F.Cu" signal "TOP")
		(4 "In1.Cu" signal "GND")
		(6 "In2.Cu" signal "VCC")
		(8 "In3.Cu" signal "VCC1")
		(10 "In4.Cu" signal "GND1")
		(12 "In5.Cu" signal "IN1")
		(14 "In6.Cu" signal "GND2")
		(16 "In7.Cu" signal "IN2")
		(18 "In8.Cu" signal "GND3")
		(20 "In9.Cu" signal "IN3")
		(22 "In10.Cu" signal "GND4")
		(24 "In11.Cu" signal "IN4")
		(26 "In12.Cu" signal "GND5")
		(28 "In13.Cu" signal "IN5")
		(30 "In14.Cu" signal "GND6")
		(32 "In15.Cu" signal "IN6")
		(34 "In16.Cu" signal "GND7")
		(2 "B.Cu" signal "BOTTOM")
		(9 "F.Adhes" user "F.Adhesive")
		(11 "B.Adhes" user "B.Adhesive")
		(13 "F.Paste" user "Package Geometry/Pastemask Top")
		(15 "B.Paste" user "Package Geometry/Pastemask Bottom")
		(5 "F.SilkS" user "Ref Des/Silkscreen Top")
		(7 "B.SilkS" user "Ref Des/Silkscreen Bottom")
		(1 "F.Mask" user "Board Geometry/Soldermask Top")
		(3 "B.Mask" user "Board Geometry/Soldermask Bottom")
		(17 "Dwgs.User" user "User.Drawings")
		(19 "Cmts.User" user "User.Comments")
		(21 "Eco1.User" user "User.Eco1")
		(23 "Eco2.User" user "User.Eco2")
		(25 "Edge.Cuts" user "Board Geometry/Outline")
		(27 "Margin" user)
		(31 "F.CrtYd" user "Package Geometry/Place Bound Top")
		(29 "B.CrtYd" user "Package Geometry/Place Bound Bottom")
		(35 "F.Fab" user "Ref Des/Assembly Top")
		(33 "B.Fab" user "Ref Des/Assembly Bottom")
	)
	(footprint ""
		(layer "F.Cu")
		(at 352.232214 -154.305)
		(property "Reference" "R4820"
			(at 0 0 0)
			(layer "F.SilkS")
			(hide yes)
			(effects
				(font
					(size 1.27 1.27)
				)
			)
		)
		(property "Value" ""
			(at 0 0 0)
			(layer "F.Fab")
			(effects
				(font
					(size 1.27 1.27)
				)
			)
		)
		(duplicate_pad_numbers_are_jumpers no)
		(fp_line
			(start -0.7874 -0.4064)
			(end 0.7874 -0.4064)
			(stroke
				(width 0.1524)
				(type default)
			)
			(layer "F.SilkS")
		)
		(fp_line
			(start -0.7874 0.4064)
			(end -0.7874 -0.4064)
			(stroke
				(width 0.1524)
				(type default)
			)
			(layer "F.SilkS")
		)
		(fp_line
			(start 0.7874 -0.4064)
			(end 0.7874 0.4064)
			(stroke
				(width 0.1524)
				(type default)
			)
			(layer "F.SilkS")
		)
		(fp_line
			(start 0.7874 0.4064)
			(end -0.7874 0.4064)
			(stroke
				(width 0.1524)
				(type default)
			)
			(layer "F.SilkS")
		)
		(fp_line
			(start -0.67945 -0.305054)
			(end -0.12065 -0.305054)
			(stroke
				(width 0.1)
				(type default)
			)
			(layer "F.Fab")
		)
		(fp_line
			(start -0.67945 0.3048)
			(end -0.67945 -0.305054)
			(stroke
				(width 0.1)
				(type default)
			)
			(layer "F.Fab")
		)
		(fp_line
			(start -0.12065 -0.305054)
			(end -0.12065 -0.2794)
			(stroke
				(width 0.1)
				(type default)
			)
			(layer "F.Fab")
		)
		(fp_line
			(start -0.12065 -0.2794)
			(end 0.12065 -0.2794)
			(stroke
				(width 0.1)
				(type default)
			)
			(layer "F.Fab")
		)
		(fp_line
			(start -0.12065 0.2794)
			(end -0.12065 0.3048)
			(stroke
				(width 0.1)
				(type default)
			)
			(layer "F.Fab")
		)
		(fp_line
			(start -0.12065 0.3048)
			(end -0.67945 0.3048)
			(stroke
				(width 0.1)
				(type default)
			)
			(layer "F.Fab")
		)
		(fp_line
			(start 0.120396 0.2794)
			(end -0.12065 0.2794)
			(stroke
				(width 0.1)
				(type default)
			)
			(layer "F.Fab")
		)
		(fp_line
			(start 0.120396 0.3048)
			(end 0.120396 0.2794)
			(stroke
				(width 0.1)
				(type default)
			)
			(layer "F.Fab")
		)
		(fp_line
			(start 0.12065 -0.3048)
			(end 0.67945 -0.3048)
			(stroke
				(width 0.1)
				(type default)
			)
			(layer "F.Fab")
		)
		(fp_line
			(start 0.12065 -0.2794)
			(end 0.12065 -0.3048)
			(stroke
				(width 0.1)
				(type default)
			)
			(layer "F.Fab")
		)
		(fp_line
			(start 0.67945 -0.3048)
			(end 0.67945 0.3048)
			(stroke
				(width 0.1)
				(type default)
			)
			(layer "F.Fab")
		)
		(fp_line
			(start 0.67945 0.3048)
			(end 0.120396 0.3048)
			(stroke
				(width 0.1)
				(type default)
			)
			(layer "F.Fab")
		)
		(pad "1" smd circle
			(at -0.40005 0)
			(size 0 0)
			(layers "F.Cu" "F.Mask" "F.Paste")
			(net "PRSNT_NIC6_FPGA_PCA9555_N")
		)
		(pad "2" smd circle
			(at 0.40005 0)
			(size 0 0)
			(layers "F.Cu" "F.Mask" "F.Paste")
			(net "PRSNT_NIC6_FPGA_R_N")
		)
	)
	(footprint ""
		(layer "F.Cu")
		(at 35.195002 -59.577986 90)
		(property "Reference" "PC518"
			(at 0 0 90)
			(layer "F.SilkS")
			(hide yes)
			(effects
				(font
					(size 1.27 1.27)
				)
			)
		)
		(property "Value" ""
			(at 0 0 90)
			(layer "F.Fab")
			(effects
				(font
					(size 1.27 1.27)
				)
			)
		)
		(duplicate_pad_numbers_are_jumpers no)
		(fp_line
			(start 0.7874 -0.4064)
			(end 0.7874 0.4064)
			(stroke
				(width 0.1524)
				(type default)
			)
			(layer "F.SilkS")
		)
		(fp_line
			(start -0.7874 -0.4064)
			(end 0.7874 -0.4064)
			(stroke
				(width 0.1524)
				(type default)
			)
			(layer "F.SilkS")
		)
		(fp_line
			(start 0.7874 0.4064)
			(end -0.7874 0.4064)
			(stroke
				(width 0.1524)
				(type default)
			)
			(layer "F.SilkS")
		)
		(fp_line
			(start -0.7874 0.4064)
			(end -0.7874 -0.4064)
			(stroke
				(width 0.1524)
				(type default)
			)
			(layer "F.SilkS")
		)
		(fp_line
			(start -0.12065 -0.305054)
			(end -0.12065 -0.2794)
			(stroke
				(width 0.1)
				(type default)
			)
			(layer "F.Fab")
		)
		(fp_line
			(start -0.67945 -0.305054)
			(end -0.12065 -0.305054)
			(stroke
				(width 0.1)
				(type default)
			)
			(layer "F.Fab")
		)
		(fp_line
			(start 0.67945 -0.3048)
			(end 0.67945 0.3048)
			(stroke
				(width 0.1)
				(type default)
			)
			(layer "F.Fab")
		)
		(fp_line
			(start 0.12065 -0.3048)
			(end 0.67945 -0.3048)
			(stroke
				(width 0.1)
				(type default)
			)
			(layer "F.Fab")
		)
		(fp_line
			(start 0.12065 -0.2794)
			(end 0.12065 -0.3048)
			(stroke
				(width 0.1)
				(type default)
			)
			(layer "F.Fab")
		)
		(fp_line
			(start -0.12065 -0.2794)
			(end 0.12065 -0.2794)
			(stroke
				(width 0.1)
				(type default)
			)
			(layer "F.Fab")
		)
		(fp_line
			(start 0.120396 0.2794)
			(end -0.12065 0.2794)
			(stroke
				(width 0.1)
				(type default)
			)
			(layer "F.Fab")
		)
		(fp_line
			(start -0.12065 0.2794)
			(end -0.12065 0.3048)
			(stroke
				(width 0.1)
				(type default)
			)
			(layer "F.Fab")
		)
		(fp_line
			(start 0.67945 0.3048)
			(end 0.120396 0.3048)
			(stroke
				(width 0.1)
				(type default)
			)
			(layer "F.Fab")
		)
		(fp_line
			(start 0.120396 0.3048)
			(end 0.120396 0.2794)
			(stroke
				(width 0.1)
				(type default)
			)
			(layer "F.Fab")
		)
		(fp_line
			(start -0.12065 0.3048)
			(end -0.67945 0.3048)
			(stroke
				(width 0.1)
				(type default)
			)
			(layer "F.Fab")
		)
		(fp_line
			(start -0.67945 0.3048)
			(end -0.67945 -0.305054)
			(stroke
				(width 0.1)
				(type default)
			)
			(layer "F.Fab")
		)
		(pad "1" smd circle
			(at -0.40005 0 90)
			(size 0 0)
			(layers "F.Cu" "F.Mask" "F.Paste")
			(net "P3V3_SSD1_SS")
		)
		(pad "2" smd circle
			(at 0.40005 0 90)
			(size 0 0)
			(layers "F.Cu" "F.Mask" "F.Paste")
			(net "GND")
		)
	)
	(footprint ""
		(layer "F.Cu")
		(at 436.775606 -122.931682 -90)
		(property "Reference" "PD59"
			(at 4.059682 2.129536 90)
			(unlocked yes)
			(layer "F.SilkS")
			(effects
				(font
					(size 0.7874 0.5842)
					(thickness 0.1524)
				)
				(justify left)
			)
		)
		(property "Value" ""
			(at 0 0 270)
			(layer "F.Fab")
			(effects
				(font
					(size 1.27 1.27)
				)
			)
		)
		(duplicate_pad_numbers_are_jumpers no)
		(fp_line
			(start -3.400044 1.459992)
			(end -3.400044 -1.459992)
			(stroke
				(width 0.1524)
				(type default)
			)
			(layer "F.SilkS")
		)
		(fp_line
			(start 4.107942 1.459992)
			(end -3.400044 1.459992)
			(stroke
				(width 0.1524)
				(type default)
			)
			(layer "F.SilkS")
		)
		(fp_line
			(start -3.400044 -1.459992)
			(end 4.107942 -1.459992)
			(stroke
				(width 0.1524)
				(type default)
			)
			(layer "F.SilkS")
		)
		(fp_line
			(start 4.107942 -1.459992)
			(end 4.107942 1.459992)
			(stroke
				(width 0.1524)
				(type default)
			)
			(layer "F.SilkS")
		)
		(fp_rect
			(start 4.107942 1.459992)
			(end 3.308096 -1.459992)
			(stroke
				(width 0)
				(type default)
			)
			(fill yes)
			(layer "F.SilkS")
		)
		(fp_line
			(start -2.29997 1.459992)
			(end -2.29997 -1.459992)
			(stroke
				(width 0.1)
				(type default)
			)
			(layer "F.Fab")
		)
		(fp_line
			(start 2.29997 1.459992)
			(end -2.29997 1.459992)
			(stroke
				(width 0.1)
				(type default)
			)
			(layer "F.Fab")
		)
		(fp_line
			(start -2.29997 -1.459992)
			(end 2.29997 -1.459992)
			(stroke
				(width 0.1)
				(type default)
			)
			(layer "F.Fab")
		)
		(fp_line
			(start 2.29997 -1.459992)
			(end 2.29997 1.459992)
			(stroke
				(width 0.1)
				(type default)
			)
			(layer "F.Fab")
		)
		(fp_text user "-"
			(at 5.4102 0.29845 90)
			(unlocked yes)
			(layer "F.SilkS")
			(effects
				(font
					(size 1.905 1.4224)
					(thickness 0.1524)
				)
				(justify left)
			)
		)
		(fp_text user "+"
			(at -4.7752 -0.12065 270)
			(unlocked yes)
			(layer "F.SilkS")
			(effects
				(font
					(size 1.905 1.4224)
					(thickness 0.1524)
				)
				(justify left)
			)
		)
		(fp_text user "-"
			(at 5.4102 0.29845 90)
			(unlocked yes)
			(layer "F.Fab")
			(effects
				(font
					(size 1.905 1.4224)
					(thickness 0.1524)
				)
				(justify left)
			)
		)
		(fp_text user "+"
			(at -4.7752 -0.12065 270)
			(unlocked yes)
			(layer "F.Fab")
			(effects
				(font
					(size 1.905 1.4224)
					(thickness 0.1524)
				)
				(justify left)
			)
		)
		(pad "A" smd rect
			(at -1.999996 0)
			(size 1.7018 2.5146)
			(layers "F.Cu" "F.Mask" "F.Paste")
			(net "GND")
		)
		(pad "C" smd rect
			(at 1.999996 0)
			(size 1.7018 2.5146)
			(layers "F.Cu" "F.Mask" "F.Paste")
			(net "P3V3_NIC7")
		)
	)
	(footprint ""
		(layer "F.Cu")
		(at 121.13514 -93.748606)
		(property "Reference" "R1554"
			(at 0 0 0)
			(layer "F.SilkS")
			(hide yes)
			(effects
				(font
					(size 1.27 1.27)
				)
			)
		)
		(property "Value" ""
			(at 0 0 0)
			(layer "F.Fab")
			(effects
				(font
					(size 1.27 1.27)
				)
			)
		)
		(duplicate_pad_numbers_are_jumpers no)
		(fp_line
			(start -0.7874 -0.4064)
			(end 0.7874 -0.4064)
			(stroke
				(width 0.1524)
				(type default)
			)
			(layer "F.SilkS")
		)
		(fp_line
			(start -0.7874 0.4064)
			(end -0.7874 -0.4064)
			(stroke
				(width 0.1524)
				(type default)
			)
			(layer "F.SilkS")
		)
		(fp_line
			(start 0.7874 -0.4064)
			(end 0.7874 0.4064)
			(stroke
				(width 0.1524)
				(type default)
			)
			(layer "F.SilkS")
		)
		(fp_line
			(start 0.7874 0.4064)
			(end -0.7874 0.4064)
			(stroke
				(width 0.1524)
				(type default)
			)
			(layer "F.SilkS")
		)
		(fp_line
			(start -0.67945 -0.305054)
			(end -0.12065 -0.305054)
			(stroke
				(width 0.1)
				(type default)
			)
			(layer "F.Fab")
		)
		(fp_line
			(start -0.67945 0.3048)
			(end -0.67945 -0.305054)
			(stroke
				(width 0.1)
				(type default)
			)
			(layer "F.Fab")
		)
		(fp_line
			(start -0.12065 -0.305054)
			(end -0.12065 -0.2794)
			(stroke
				(width 0.1)
				(type default)
			)
			(layer "F.Fab")
		)
		(fp_line
			(start -0.12065 -0.2794)
			(end 0.12065 -0.2794)
			(stroke
				(width 0.1)
				(type default)
			)
			(layer "F.Fab")
		)
		(fp_line
			(start -0.12065 0.2794)
			(end -0.12065 0.3048)
			(stroke
				(width 0.1)
				(type default)
			)
			(layer "F.Fab")
		)
		(fp_line
			(start -0.12065 0.3048)
			(end -0.67945 0.3048)
			(stroke
				(width 0.1)
				(type default)
			)
			(layer "F.Fab")
		)
		(fp_line
			(start 0.120396 0.2794)
			(end -0.12065 0.2794)
			(stroke
				(width 0.1)
				(type default)
			)
			(layer "F.Fab")
		)
		(fp_line
			(start 0.120396 0.3048)
			(end 0.120396 0.2794)
			(stroke
				(width 0.1)
				(type default)
			)
			(layer "F.Fab")
		)
		(fp_line
			(start 0.12065 -0.3048)
			(end 0.67945 -0.3048)
			(stroke
				(width 0.1)
				(type default)
			)
			(layer "F.Fab")
		)
		(fp_line
			(start 0.12065 -0.2794)
			(end 0.12065 -0.3048)
			(stroke
				(width 0.1)
				(type default)
			)
			(layer "F.Fab")
		)
		(fp_line
			(start 0.67945 -0.3048)
			(end 0.67945 0.3048)
			(stroke
				(width 0.1)
				(type default)
			)
			(layer "F.Fab")
		)
		(fp_line
			(start 0.67945 0.3048)
			(end 0.120396 0.3048)
			(stroke
				(width 0.1)
				(type default)
			)
			(layer "F.Fab")
		)
		(pad "1" smd circle
			(at -0.40005 0)
			(size 0 0)
			(layers "F.Cu" "F.Mask" "F.Paste")
			(net "P3V3_AUX")
		)
		(pad "2" smd circle
			(at 0.40005 0)
			(size 0 0)
			(layers "F.Cu" "F.Mask" "F.Paste")
			(net "SMB_BIC_I2C9_MUX0_SSD1_R_SCL")
		)
	)
	(footprint ""
		(layer "F.Cu")
		(at 240.580164 -57.620408)
		(property "Reference" "R4498"
			(at 0 0 0)
			(layer "F.SilkS")
			(hide yes)
			(effects
				(font
					(size 1.27 1.27)
				)
			)
		)
		(property "Value" ""
			(at 0 0 0)
			(layer "F.Fab")
			(effects
				(font
					(size 1.27 1.27)
				)
			)
		)
		(duplicate_pad_numbers_are_jumpers no)
		(fp_line
			(start -0.7874 -0.4064)
			(end 0.7874 -0.4064)
			(stroke
				(width 0.1524)
				(type default)
			)
			(layer "F.SilkS")
		)
		(fp_line
			(start -0.7874 0.4064)
			(end -0.7874 -0.4064)
			(stroke
				(width 0.1524)
				(type default)
			)
			(layer "F.SilkS")
		)
		(fp_line
			(start 0.7874 -0.4064)
			(end 0.7874 0.4064)
			(stroke
				(width 0.1524)
				(type default)
			)
			(layer "F.SilkS")
		)
		(fp_line
			(start 0.7874 0.4064)
			(end -0.7874 0.4064)
			(stroke
				(width 0.1524)
				(type default)
			)
			(layer "F.SilkS")
		)
		(fp_line
			(start -0.67945 -0.305054)
			(end -0.12065 -0.305054)
			(stroke
				(width 0.1)
				(type default)
			)
			(layer "F.Fab")
		)
		(fp_line
			(start -0.67945 0.3048)
			(end -0.67945 -0.305054)
			(stroke
				(width 0.1)
				(type default)
			)
			(layer "F.Fab")
		)
		(fp_line
			(start -0.12065 -0.305054)
			(end -0.12065 -0.2794)
			(stroke
				(width 0.1)
				(type default)
			)
			(layer "F.Fab")
		)
		(fp_line
			(start -0.12065 -0.2794)
			(end 0.12065 -0.2794)
			(stroke
				(width 0.1)
				(type default)
			)
			(layer "F.Fab")
		)
		(fp_line
			(start -0.12065 0.2794)
			(end -0.12065 0.3048)
			(stroke
				(width 0.1)
				(type default)
			)
			(layer "F.Fab")
		)
		(fp_line
			(start -0.12065 0.3048)
			(end -0.67945 0.3048)
			(stroke
				(width 0.1)
				(type default)
			)
			(layer "F.Fab")
		)
		(fp_line
			(start 0.120396 0.2794)
			(end -0.12065 0.2794)
			(stroke
				(width 0.1)
				(type default)
			)
			(layer "F.Fab")
		)
		(fp_line
			(start 0.120396 0.3048)
			(end 0.120396 0.2794)
			(stroke
				(width 0.1)
				(type default)
			)
			(layer "F.Fab")
		)
		(fp_line
			(start 0.12065 -0.3048)
			(end 0.67945 -0.3048)
			(stroke
				(width 0.1)
				(type default)
			)
			(layer "F.Fab")
		)
		(fp_line
			(start 0.12065 -0.2794)
			(end 0.12065 -0.3048)
			(stroke
				(width 0.1)
				(type default)
			)
			(layer "F.Fab")
		)
		(fp_line
			(start 0.67945 -0.3048)
			(end 0.67945 0.3048)
			(stroke
				(width 0.1)
				(type default)
			)
			(layer "F.Fab")
		)
		(fp_line
			(start 0.67945 0.3048)
			(end 0.120396 0.3048)
			(stroke
				(width 0.1)
				(type default)
			)
			(layer "F.Fab")
		)
		(pad "1" smd circle
			(at -0.40005 0)
			(size 0 0)
			(layers "F.Cu" "F.Mask" "F.Paste")
			(net "PWRGD_P3V3_SSD8")
		)
		(pad "2" smd circle
			(at 0.40005 0)
			(size 0 0)
			(layers "F.Cu" "F.Mask" "F.Paste")
			(net "PWRGD_P3V3_SSD8_R")
		)
	)
	(footprint ""
		(layer "F.Cu")
		(at 386.866384 -252.356874 -90)
		(property "Reference" "R1424"
			(at 0 0 270)
			(layer "F.SilkS")
			(hide yes)
			(effects
				(font
					(size 1.27 1.27)
				)
			)
		)
		(property "Value" ""
			(at 0 0 270)
			(layer "F.Fab")
			(effects
				(font
					(size 1.27 1.27)
				)
			)
		)
		(duplicate_pad_numbers_are_jumpers no)
		(fp_line
			(start -0.7874 0.4064)
			(end -0.7874 -0.4064)
			(stroke
				(width 0.1524)
				(type default)
			)
			(layer "F.SilkS")
		)
		(fp_line
			(start 0.7874 0.4064)
			(end -0.7874 0.4064)
			(stroke
				(width 0.1524)
				(type default)
			)
			(layer "F.SilkS")
		)
		(fp_line
			(start -0.7874 -0.4064)
			(end 0.7874 -0.4064)
			(stroke
				(width 0.1524)
				(type default)
			)
			(layer "F.SilkS")
		)
		(fp_line
			(start 0.7874 -0.4064)
			(end 0.7874 0.4064)
			(stroke
				(width 0.1524)
				(type default)
			)
			(layer "F.SilkS")
		)
		(fp_line
			(start -0.67945 0.3048)
			(end -0.67945 -0.305054)
			(stroke
				(width 0.1)
				(type default)
			)
			(layer "F.Fab")
		)
		(fp_line
			(start -0.12065 0.3048)
			(end -0.67945 0.3048)
			(stroke
				(width 0.1)
				(type default)
			)
			(layer "F.Fab")
		)
		(fp_line
			(start 0.120396 0.3048)
			(end 0.120396 0.2794)
			(stroke
				(width 0.1)
				(type default)
			)
			(layer "F.Fab")
		)
		(fp_line
			(start 0.67945 0.3048)
			(end 0.120396 0.3048)
			(stroke
				(width 0.1)
				(type default)
			)
			(layer "F.Fab")
		)
		(fp_line
			(start -0.12065 0.2794)
			(end -0.12065 0.3048)
			(stroke
				(width 0.1)
				(type default)
			)
			(layer "F.Fab")
		)
		(fp_line
			(start 0.120396 0.2794)
			(end -0.12065 0.2794)
			(stroke
				(width 0.1)
				(type default)
			)
			(layer "F.Fab")
		)
		(fp_line
			(start -0.12065 -0.2794)
			(end 0.12065 -0.2794)
			(stroke
				(width 0.1)
				(type default)
			)
			(layer "F.Fab")
		)
		(fp_line
			(start 0.12065 -0.2794)
			(end 0.12065 -0.3048)
			(stroke
				(width 0.1)
				(type default)
			)
			(layer "F.Fab")
		)
		(fp_line
			(start 0.12065 -0.3048)
			(end 0.67945 -0.3048)
			(stroke
				(width 0.1)
				(type default)
			)
			(layer "F.Fab")
		)
		(fp_line
			(start 0.67945 -0.3048)
			(end 0.67945 0.3048)
			(stroke
				(width 0.1)
				(type default)
			)
			(layer "F.Fab")
		)
		(fp_line
			(start -0.67945 -0.305054)
			(end -0.12065 -0.305054)
			(stroke
				(width 0.1)
				(type default)
			)
			(layer "F.Fab")
		)
		(fp_line
			(start -0.12065 -0.305054)
			(end -0.12065 -0.2794)
			(stroke
				(width 0.1)
				(type default)
			)
			(layer "F.Fab")
		)
		(pad "1" smd circle
			(at -0.40005 0 270)
			(size 0 0)
			(layers "F.Cu" "F.Mask" "F.Paste")
			(net "GND")
		)
		(pad "2" smd circle
			(at 0.40005 0 270)
			(size 0 0)
			(layers "F.Cu" "F.Mask" "F.Paste")
			(net "PEX3_DBG_MODE4")
		)
	)
)
